(kicad_pcb
	(version 20260206)
	(generator "pcbnew")
	(generator_version "10.0")
	(general
		(thickness 1.6)
		(legacy_teardrops no)
	)
	(paper "A4")
	(title_block
		(title "peb — Lightning_PEB_BRD.brd")
		(comment 1 "Lightning (Wiwynn / Facebook NVMe JBOF) / footprints 656-663 of 2563")
	)
	(layers
		(0 "F.Cu" signal "TOP")
		(4 "In1.Cu" signal "L2GND")
		(6 "In2.Cu" signal "L3")
		(8 "In3.Cu" signal "L4VCC")
		(10 "In4.Cu" signal "L5VCC")
		(12 "In5.Cu" signal "L6")
		(14 "In6.Cu" signal "L7GND")
		(2 "B.Cu" signal "BOTTOM")
		(9 "F.Adhes" user "F.Adhesive")
		(11 "B.Adhes" user "B.Adhesive")
		(13 "F.Paste" user "Package Geometry/Pastemask Top")
		(15 "B.Paste" user "Package Geometry/Pastemask Bottom")
		(5 "F.SilkS" user "Ref Des/Silkscreen Top")
		(7 "B.SilkS" user "Ref Des/Silkscreen Bottom")
		(1 "F.Mask" user "Board Geometry/Soldermask Top")
		(3 "B.Mask" user "Board Geometry/Soldermask Bottom")
		(17 "Dwgs.User" user "User.Drawings")
		(19 "Cmts.User" user "User.Comments")
		(21 "Eco1.User" user "User.Eco1")
		(23 "Eco2.User" user "User.Eco2")
		(25 "Edge.Cuts" user "Board Geometry/Outline")
		(27 "Margin" user)
		(31 "F.CrtYd" user "Package Geometry/Place Bound Top")
		(29 "B.CrtYd" user "Package Geometry/Place Bound Bottom")
		(35 "F.Fab" user "Ref Des/Assembly Top")
		(33 "B.Fab" user "Ref Des/Assembly Bottom")
	)
	(footprint ""
		(layer "F.Cu")
		(at 288.544 -59.563 -90)
		(property "Reference" "R424"
			(at 0 0 270)
			(layer "F.SilkS")
			(hide yes)
			(effects
				(font
					(size 1.27 1.27)
				)
			)
		)
		(property "Value" "0R2J-2-GP"
			(at 0.064008 -3.993896 270)
			(unlocked yes)
			(layer "F.Fab")
			(hide yes)
			(effects
				(font
					(size 1.016 1.016)
					(thickness 0.1524)
				)
			)
		)
		(property "Device Type" "R402H16"
			(at 0.064008 -5.517896 270)
			(unlocked yes)
			(layer "F.Fab")
			(hide yes)
			(effects
				(font
					(size 1.016 1.016)
					(thickness 0.1524)
				)
			)
		)
		(duplicate_pad_numbers_are_jumpers no)
		(fp_line
			(start -0.508 -0.9398)
			(end -0.508 0.9398)
			(stroke
				(width 0.1524)
				(type default)
			)
			(layer "F.SilkS")
		)
		(fp_line
			(start 0.508 -0.9398)
			(end -0.508 -0.9398)
			(stroke
				(width 0.1524)
				(type default)
			)
			(layer "F.SilkS")
		)
		(fp_rect
			(start -0.508 0.9398)
			(end 0.508 -0.9398)
			(stroke
				(width 0)
				(type default)
			)
			(fill no)
			(layer "F.CrtYd")
		)
		(fp_rect
			(start -0.508 0.9398)
			(end 0.508 -0.9398)
			(stroke
				(width 0)
				(type default)
			)
			(fill no)
			(layer "F.Fab")
		)
		(pad "1" smd custom
			(at 0 -0.4445 270)
			(size 0.1397 0.1397)
			(layers "F.Cu" "F.Mask" "F.Paste")
			(net "VS5_LED_R")
			(options
				(clearance outline)
				(anchor circle)
			)
			(primitives
				(gr_poly
					(pts
						(arc
							(start -0.1778 -0.2794)
							(mid -0.249642 -0.249642)
							(end -0.2794 -0.1778)
						)
						(arc
							(start -0.2794 0.1778)
							(mid -0.249642 0.249642)
							(end -0.1778 0.2794)
						)
						(arc
							(start 0.1778 0.2794)
							(mid 0.249642 0.249642)
							(end 0.2794 0.1778)
						)
						(arc
							(start 0.2794 -0.1778)
							(mid 0.249642 -0.249642)
							(end 0.1778 -0.2794)
						)
					)
					(width 0)
					(fill yes)
				)
			)
		)
		(pad "2" smd custom
			(at 0 0.4445 270)
			(size 0.1397 0.1397)
			(layers "F.Cu" "F.Mask" "F.Paste")
			(net "VS5_LED")
			(options
				(clearance outline)
				(anchor circle)
			)
			(primitives
				(gr_poly
					(pts
						(arc
							(start -0.1778 -0.2794)
							(mid -0.249642 -0.249642)
							(end -0.2794 -0.1778)
						)
						(arc
							(start -0.2794 0.1778)
							(mid -0.249642 0.249642)
							(end -0.1778 0.2794)
						)
						(arc
							(start 0.1778 0.2794)
							(mid 0.249642 0.249642)
							(end 0.2794 0.1778)
						)
						(arc
							(start 0.2794 -0.1778)
							(mid 0.249642 -0.249642)
							(end 0.1778 -0.2794)
						)
					)
					(width 0)
					(fill yes)
				)
			)
		)
	)
	(footprint ""
		(layer "F.Cu")
		(at 31.369 -45.974 -90)
		(property "Reference" "C337"
			(at 0 0 270)
			(layer "F.SilkS")
			(hide yes)
			(effects
				(font
					(size 1.27 1.27)
				)
			)
		)
		(property "Value" "SC1U10V2KX-4-GP"
			(at 1.1811 -2.7051 270)
			(unlocked yes)
			(layer "F.Fab")
			(hide yes)
			(effects
				(font
					(size 1.016 1.016)
					(thickness 0.1524)
				)
			)
		)
		(property "Device Type" "C402H22"
			(at 1.1811 -4.2291 270)
			(unlocked yes)
			(layer "F.Fab")
			(hide yes)
			(effects
				(font
					(size 1.016 1.016)
					(thickness 0.1524)
				)
			)
		)
		(duplicate_pad_numbers_are_jumpers no)
		(fp_rect
			(start -0.4318 0.9525)
			(end 0.4318 -0.9525)
			(stroke
				(width 0)
				(type default)
			)
			(fill no)
			(layer "F.CrtYd")
		)
		(fp_rect
			(start -0.4318 0.9525)
			(end 0.4318 -0.9525)
			(stroke
				(width 0)
				(type default)
			)
			(fill no)
			(layer "F.Fab")
		)
		(pad "1" smd custom
			(at 0 -0.4445 270)
			(size 0.1524 0.1524)
			(layers "F.Cu" "F.Mask" "F.Paste")
			(net "P5V_USB")
			(options
				(clearance outline)
				(anchor circle)
			)
			(primitives
				(gr_poly
					(pts
						(arc
							(start 0.3048 -0.2032)
							(mid 0.275042 -0.275042)
							(end 0.2032 -0.3048)
						)
						(arc
							(start -0.2032 -0.3048)
							(mid -0.275042 -0.275042)
							(end -0.3048 -0.2032)
						)
						(arc
							(start -0.3048 0.2032)
							(mid -0.275042 0.275042)
							(end -0.2032 0.3048)
						)
						(arc
							(start 0.2032 0.3048)
							(mid 0.275042 0.275042)
							(end 0.3048 0.2032)
						)
					)
					(width 0)
					(fill yes)
				)
			)
		)
		(pad "2" smd custom
			(at 0 0.4445 270)
			(size 0.1524 0.1524)
			(layers "F.Cu" "F.Mask" "F.Paste")
			(net "GND")
			(options
				(clearance outline)
				(anchor circle)
			)
			(primitives
				(gr_poly
					(pts
						(arc
							(start 0.3048 -0.2032)
							(mid 0.275042 -0.275042)
							(end 0.2032 -0.3048)
						)
						(arc
							(start -0.2032 -0.3048)
							(mid -0.275042 -0.275042)
							(end -0.3048 -0.2032)
						)
						(arc
							(start -0.3048 0.2032)
							(mid -0.275042 0.275042)
							(end -0.2032 0.3048)
						)
						(arc
							(start 0.2032 0.3048)
							(mid 0.275042 0.275042)
							(end 0.3048 0.2032)
						)
					)
					(width 0)
					(fill yes)
				)
			)
		)
	)
	(footprint ""
		(layer "F.Cu")
		(at 52.1208 -50.3174)
		(property "Reference" "C236"
			(at 0 0 0)
			(layer "F.SilkS")
			(hide yes)
			(effects
				(font
					(size 1.27 1.27)
				)
			)
		)
		(property "Value" "SC1U10V2KX-4-GP"
			(at 1.1811 -2.7051 0)
			(unlocked yes)
			(layer "F.Fab")
			(hide yes)
			(effects
				(font
					(size 1.016 1.016)
					(thickness 0.1524)
				)
			)
		)
		(property "Device Type" "C402H22"
			(at 1.1811 -4.2291 0)
			(unlocked yes)
			(layer "F.Fab")
			(hide yes)
			(effects
				(font
					(size 1.016 1.016)
					(thickness 0.1524)
				)
			)
		)
		(duplicate_pad_numbers_are_jumpers no)
		(fp_rect
			(start -0.4318 0.9525)
			(end 0.4318 -0.9525)
			(stroke
				(width 0)
				(type default)
			)
			(fill no)
			(layer "F.CrtYd")
		)
		(fp_rect
			(start -0.4318 0.9525)
			(end 0.4318 -0.9525)
			(stroke
				(width 0)
				(type default)
			)
			(fill no)
			(layer "F.Fab")
		)
		(pad "1" smd custom
			(at 0 -0.4445)
			(size 0.1524 0.1524)
			(layers "F.Cu" "F.Mask" "F.Paste")
			(net "P3V3_STBY")
			(options
				(clearance outline)
				(anchor circle)
			)
			(primitives
				(gr_poly
					(pts
						(arc
							(start 0.3048 -0.2032)
							(mid 0.275042 -0.275042)
							(end 0.2032 -0.3048)
						)
						(arc
							(start -0.2032 -0.3048)
							(mid -0.275042 -0.275042)
							(end -0.3048 -0.2032)
						)
						(arc
							(start -0.3048 0.2032)
							(mid -0.275042 0.275042)
							(end -0.2032 0.3048)
						)
						(arc
							(start 0.2032 0.3048)
							(mid 0.275042 0.275042)
							(end 0.3048 0.2032)
						)
					)
					(width 0)
					(fill yes)
				)
			)
		)
		(pad "2" smd custom
			(at 0 0.4445)
			(size 0.1524 0.1524)
			(layers "F.Cu" "F.Mask" "F.Paste")
			(net "GND")
			(options
				(clearance outline)
				(anchor circle)
			)
			(primitives
				(gr_poly
					(pts
						(arc
							(start 0.3048 -0.2032)
							(mid 0.275042 -0.275042)
							(end 0.2032 -0.3048)
						)
						(arc
							(start -0.2032 -0.3048)
							(mid -0.275042 -0.275042)
							(end -0.3048 -0.2032)
						)
						(arc
							(start -0.3048 0.2032)
							(mid -0.275042 0.275042)
							(end -0.2032 0.3048)
						)
						(arc
							(start 0.2032 0.3048)
							(mid 0.275042 0.275042)
							(end 0.3048 0.2032)
						)
					)
					(width 0)
					(fill yes)
				)
			)
		)
	)
	(footprint ""
		(layer "F.Cu")
		(at 335.6356 -76.1746 180)
		(property "Reference" "PR182"
			(at 0 0 180)
			(layer "F.SilkS")
			(hide yes)
			(effects
				(font
					(size 1.27 1.27)
				)
			)
		)
		(property "Value" "80K6R2F-GP"
			(at 0.064008 -3.993896 180)
			(unlocked yes)
			(layer "F.Fab")
			(hide yes)
			(effects
				(font
					(size 1.016 1.016)
					(thickness 0.1524)
				)
			)
		)
		(property "Device Type" "R402H16"
			(at 0.064008 -5.517896 180)
			(unlocked yes)
			(layer "F.Fab")
			(hide yes)
			(effects
				(font
					(size 1.016 1.016)
					(thickness 0.1524)
				)
			)
		)
		(duplicate_pad_numbers_are_jumpers no)
		(fp_line
			(start 0.508 -0.9398)
			(end -0.508 -0.9398)
			(stroke
				(width 0.1524)
				(type default)
			)
			(layer "F.SilkS")
		)
		(fp_line
			(start -0.508 -0.9398)
			(end -0.508 0.9398)
			(stroke
				(width 0.1524)
				(type default)
			)
			(layer "F.SilkS")
		)
		(fp_rect
			(start -0.508 0.9398)
			(end 0.508 -0.9398)
			(stroke
				(width 0)
				(type default)
			)
			(fill no)
			(layer "F.CrtYd")
		)
		(fp_rect
			(start -0.508 0.9398)
			(end 0.508 -0.9398)
			(stroke
				(width 0)
				(type default)
			)
			(fill no)
			(layer "F.Fab")
		)
		(pad "1" smd custom
			(at 0 -0.4445 180)
			(size 0.1397 0.1397)
			(layers "F.Cu" "F.Mask" "F.Paste")
			(net "P0V9_E_VFB")
			(options
				(clearance outline)
				(anchor circle)
			)
			(primitives
				(gr_poly
					(pts
						(arc
							(start -0.1778 -0.2794)
							(mid -0.249642 -0.249642)
							(end -0.2794 -0.1778)
						)
						(arc
							(start -0.2794 0.1778)
							(mid -0.249642 0.249642)
							(end -0.1778 0.2794)
						)
						(arc
							(start 0.1778 0.2794)
							(mid 0.249642 0.249642)
							(end 0.2794 0.1778)
						)
						(arc
							(start 0.2794 -0.1778)
							(mid 0.249642 -0.249642)
							(end 0.1778 -0.2794)
						)
					)
					(width 0)
					(fill yes)
				)
			)
		)
		(pad "2" smd custom
			(at 0 0.4445 180)
			(size 0.1397 0.1397)
			(layers "F.Cu" "F.Mask" "F.Paste")
			(net "P0V9_E_VFB_AVS")
			(options
				(clearance outline)
				(anchor circle)
			)
			(primitives
				(gr_poly
					(pts
						(arc
							(start -0.1778 -0.2794)
							(mid -0.249642 -0.249642)
							(end -0.2794 -0.1778)
						)
						(arc
							(start -0.2794 0.1778)
							(mid -0.249642 0.249642)
							(end -0.1778 0.2794)
						)
						(arc
							(start 0.1778 0.2794)
							(mid 0.249642 0.249642)
							(end 0.2794 0.1778)
						)
						(arc
							(start 0.2794 -0.1778)
							(mid 0.249642 -0.249642)
							(end 0.1778 -0.2794)
						)
					)
					(width 0)
					(fill yes)
				)
			)
		)
	)
	(footprint ""
		(layer "F.Cu")
		(at 45.618146 -116.199666)
		(property "Reference" "TP217"
			(at 0 0 0)
			(layer "F.SilkS")
			(hide yes)
			(effects
				(font
					(size 1.27 1.27)
				)
			)
		)
		(property "Value" "TPAD28-2-GP"
			(at -0.0127 -1.6637 0)
			(unlocked yes)
			(layer "F.Fab")
			(hide yes)
			(effects
				(font
					(size 1.016 1.016)
					(thickness 0.1524)
				)
			)
		)
		(property "Device Type" "TPAD28"
			(at -0.0127 -3.1877 0)
			(unlocked yes)
			(layer "F.Fab")
			(hide yes)
			(effects
				(font
					(size 1.016 1.016)
					(thickness 0.1524)
				)
			)
		)
		(duplicate_pad_numbers_are_jumpers no)
		(fp_poly
			(pts
				(arc
					(start 0.3556 0)
					(mid -0.3556 0)
					(end 0.3556 0)
				)
			)
			(stroke
				(width 0)
				(type default)
			)
			(fill no)
			(layer "F.CrtYd")
		)
		(fp_poly
			(pts
				(arc
					(start 0.6096 0)
					(mid -0.6096 0)
					(end 0.6096 0)
				)
			)
			(stroke
				(width 0)
				(type default)
			)
			(fill no)
			(layer "F.Fab")
		)
		(pad "1" smd circle
			(at 0 0)
			(size 0.7112 0.7112)
			(layers "F.Cu" "F.Mask" "F.Paste")
			(net "GPIOH2")
		)
	)
	(footprint ""
		(layer "F.Cu")
		(at 58.928 -148.844 -90)
		(property "Reference" "R159"
			(at 0 0 270)
			(layer "F.SilkS")
			(hide yes)
			(effects
				(font
					(size 1.27 1.27)
				)
			)
		)
		(property "Value" "0R2J-2-GP"
			(at 0.064008 -3.993896 270)
			(unlocked yes)
			(layer "F.Fab")
			(hide yes)
			(effects
				(font
					(size 1.016 1.016)
					(thickness 0.1524)
				)
			)
		)
		(property "Device Type" "R402H16"
			(at 0.064008 -5.517896 270)
			(unlocked yes)
			(layer "F.Fab")
			(hide yes)
			(effects
				(font
					(size 1.016 1.016)
					(thickness 0.1524)
				)
			)
		)
		(duplicate_pad_numbers_are_jumpers no)
		(fp_line
			(start -0.508 -0.9398)
			(end -0.508 0.9398)
			(stroke
				(width 0.1524)
				(type default)
			)
			(layer "F.SilkS")
		)
		(fp_line
			(start 0.508 -0.9398)
			(end -0.508 -0.9398)
			(stroke
				(width 0.1524)
				(type default)
			)
			(layer "F.SilkS")
		)
		(fp_rect
			(start -0.508 0.9398)
			(end 0.508 -0.9398)
			(stroke
				(width 0)
				(type default)
			)
			(fill no)
			(layer "F.CrtYd")
		)
		(fp_rect
			(start -0.508 0.9398)
			(end 0.508 -0.9398)
			(stroke
				(width 0)
				(type default)
			)
			(fill no)
			(layer "F.Fab")
		)
		(pad "1" smd custom
			(at 0 -0.4445 270)
			(size 0.1397 0.1397)
			(layers "F.Cu" "F.Mask" "F.Paste")
			(net "BMC_I2C5_D_PEB_SDA")
			(options
				(clearance outline)
				(anchor circle)
			)
			(primitives
				(gr_poly
					(pts
						(arc
							(start -0.1778 -0.2794)
							(mid -0.249642 -0.249642)
							(end -0.2794 -0.1778)
						)
						(arc
							(start -0.2794 0.1778)
							(mid -0.249642 0.249642)
							(end -0.1778 0.2794)
						)
						(arc
							(start 0.1778 0.2794)
							(mid 0.249642 0.249642)
							(end 0.2794 0.1778)
						)
						(arc
							(start 0.2794 -0.1778)
							(mid 0.249642 -0.249642)
							(end 0.1778 -0.2794)
						)
					)
					(width 0)
					(fill yes)
				)
			)
		)
		(pad "2" smd custom
			(at 0 0.4445 270)
			(size 0.1397 0.1397)
			(layers "F.Cu" "F.Mask" "F.Paste")
			(net "TEMP_2_SDA")
			(options
				(clearance outline)
				(anchor circle)
			)
			(primitives
				(gr_poly
					(pts
						(arc
							(start -0.1778 -0.2794)
							(mid -0.249642 -0.249642)
							(end -0.2794 -0.1778)
						)
						(arc
							(start -0.2794 0.1778)
							(mid -0.249642 0.249642)
							(end -0.1778 0.2794)
						)
						(arc
							(start 0.1778 0.2794)
							(mid 0.249642 0.249642)
							(end 0.2794 0.1778)
						)
						(arc
							(start 0.2794 -0.1778)
							(mid 0.249642 -0.249642)
							(end 0.1778 -0.2794)
						)
					)
					(width 0)
					(fill yes)
				)
			)
		)
	)
	(footprint ""
		(layer "F.Cu")
		(at 212.916008 -4.064)
		(property "Reference" "R677"
			(at 0 0 0)
			(layer "F.SilkS")
			(hide yes)
			(effects
				(font
					(size 1.27 1.27)
				)
			)
		)
		(property "Value" "100KR2F-L1-GP"
			(at 0.064008 -3.993896 0)
			(unlocked yes)
			(layer "F.Fab")
			(hide yes)
			(effects
				(font
					(size 1.016 1.016)
					(thickness 0.1524)
				)
			)
		)
		(property "Device Type" "R402H16"
			(at 0.064008 -5.517896 0)
			(unlocked yes)
			(layer "F.Fab")
			(hide yes)
			(effects
				(font
					(size 1.016 1.016)
					(thickness 0.1524)
				)
			)
		)
		(duplicate_pad_numbers_are_jumpers no)
		(fp_line
			(start -0.508 -0.9398)
			(end -0.508 0.9398)
			(stroke
				(width 0.1524)
				(type default)
			)
			(layer "F.SilkS")
		)
		(fp_line
			(start 0.508 -0.9398)
			(end -0.508 -0.9398)
			(stroke
				(width 0.1524)
				(type default)
			)
			(layer "F.SilkS")
		)
		(fp_rect
			(start -0.508 0.9398)
			(end 0.508 -0.9398)
			(stroke
				(width 0)
				(type default)
			)
			(fill no)
			(layer "F.CrtYd")
		)
		(fp_rect
			(start -0.508 0.9398)
			(end 0.508 -0.9398)
			(stroke
				(width 0)
				(type default)
			)
			(fill no)
			(layer "F.Fab")
		)
		(pad "1" smd custom
			(at 0 -0.4445)
			(size 0.1397 0.1397)
			(layers "F.Cu" "F.Mask" "F.Paste")
			(net "HOST4_RST_N")
			(options
				(clearance outline)
				(anchor circle)
			)
			(primitives
				(gr_poly
					(pts
						(arc
							(start -0.1778 -0.2794)
							(mid -0.249642 -0.249642)
							(end -0.2794 -0.1778)
						)
						(arc
							(start -0.2794 0.1778)
							(mid -0.249642 0.249642)
							(end -0.1778 0.2794)
						)
						(arc
							(start 0.1778 0.2794)
							(mid 0.249642 0.249642)
							(end 0.2794 0.1778)
						)
						(arc
							(start 0.2794 -0.1778)
							(mid 0.249642 -0.249642)
							(end 0.1778 -0.2794)
						)
					)
					(width 0)
					(fill yes)
				)
			)
		)
		(pad "2" smd custom
			(at 0 0.4445)
			(size 0.1397 0.1397)
			(layers "F.Cu" "F.Mask" "F.Paste")
			(net "GND")
			(options
				(clearance outline)
				(anchor circle)
			)
			(primitives
				(gr_poly
					(pts
						(arc
							(start -0.1778 -0.2794)
							(mid -0.249642 -0.249642)
							(end -0.2794 -0.1778)
						)
						(arc
							(start -0.2794 0.1778)
							(mid -0.249642 0.249642)
							(end -0.1778 0.2794)
						)
						(arc
							(start 0.1778 0.2794)
							(mid 0.249642 0.249642)
							(end 0.2794 0.1778)
						)
						(arc
							(start 0.2794 -0.1778)
							(mid 0.249642 -0.249642)
							(end 0.1778 -0.2794)
						)
					)
					(width 0)
					(fill yes)
				)
			)
		)
	)
	(footprint ""
		(layer "F.Cu")
		(at 22.1996 -91.44 90)
		(property "Reference" "R2942"
			(at 0 0 90)
			(layer "F.SilkS")
			(hide yes)
			(effects
				(font
					(size 1.27 1.27)
				)
			)
		)
		(property "Value" "47KR2F-GP"
			(at 0.064008 -3.993896 90)
			(unlocked yes)
			(layer "F.Fab")
			(hide yes)
			(effects
				(font
					(size 1.016 1.016)
					(thickness 0.1524)
				)
			)
		)
		(property "Device Type" "R402H16"
			(at 0.064008 -5.517896 90)
			(unlocked yes)
			(layer "F.Fab")
			(hide yes)
			(effects
				(font
					(size 1.016 1.016)
					(thickness 0.1524)
				)
			)
		)
		(duplicate_pad_numbers_are_jumpers no)
		(fp_line
			(start 0.508 -0.9398)
			(end -0.508 -0.9398)
			(stroke
				(width 0.1524)
				(type default)
			)
			(layer "F.SilkS")
		)
		(fp_line
			(start -0.508 -0.9398)
			(end -0.508 0.9398)
			(stroke
				(width 0.1524)
				(type default)
			)
			(layer "F.SilkS")
		)
		(fp_rect
			(start -0.508 0.9398)
			(end 0.508 -0.9398)
			(stroke
				(width 0)
				(type default)
			)
			(fill no)
			(layer "F.CrtYd")
		)
		(fp_rect
			(start -0.508 0.9398)
			(end 0.508 -0.9398)
			(stroke
				(width 0)
				(type default)
			)
			(fill no)
			(layer "F.Fab")
		)
		(pad "1" smd custom
			(at 0 -0.4445 90)
			(size 0.1397 0.1397)
			(layers "F.Cu" "F.Mask" "F.Paste")
			(net "FM_TPM_PRES_RST_N")
			(options
				(clearance outline)
				(anchor circle)
			)
			(primitives
				(gr_poly
					(pts
						(arc
							(start -0.1778 -0.2794)
							(mid -0.249642 -0.249642)
							(end -0.2794 -0.1778)
						)
						(arc
							(start -0.2794 0.1778)
							(mid -0.249642 0.249642)
							(end -0.1778 0.2794)
						)
						(arc
							(start 0.1778 0.2794)
							(mid 0.249642 0.249642)
							(end 0.2794 0.1778)
						)
						(arc
							(start 0.2794 -0.1778)
							(mid 0.249642 -0.249642)
							(end 0.1778 -0.2794)
						)
					)
					(width 0)
					(fill yes)
				)
			)
		)
		(pad "2" smd custom
			(at 0 0.4445 90)
			(size 0.1397 0.1397)
			(layers "F.Cu" "F.Mask" "F.Paste")
			(net "FM_TPM_PRES_RST_N_R")
			(options
				(clearance outline)
				(anchor circle)
			)
			(primitives
				(gr_poly
					(pts
						(arc
							(start -0.1778 -0.2794)
							(mid -0.249642 -0.249642)
							(end -0.2794 -0.1778)
						)
						(arc
							(start -0.2794 0.1778)
							(mid -0.249642 0.249642)
							(end -0.1778 0.2794)
						)
						(arc
							(start 0.1778 0.2794)
							(mid 0.249642 0.249642)
							(end 0.2794 0.1778)
						)
						(arc
							(start 0.2794 -0.1778)
							(mid 0.249642 -0.249642)
							(end 0.1778 -0.2794)
						)
					)
					(width 0)
					(fill yes)
				)
			)
		)
	)
)
